# BASEBOARD_FAB2 (Tioga Pass) — schematic netlist excerpt (pin names and nets, part order shuffled) for the footprints in the layout excerpt that follows; sources: Cadence DE-HDL packaged netlist, KiCad conversion of Wiwynn_Tioga_Pass_MB.brd

Q6W1  FET_N  2N7002 FET  pkg SOT23LF  page 200
  GATE  = UV_HIGH_SET
  SRC  = GND
  DRN  = UV_HIGH_SET_N

C8P32  CAP  100UF 4V 20% X5R  pkg 0805  page 225 : A = PVDDQ_GHJ ; B = GND
C3M21  CAP_A  1.0UF 6.3V 10% X6S  pkg 0402V  page 127 : A = P1V05_PCH_STBY ; B = GND

(kicad_pcb
	(version 20260206)
	(generator "pcbnew")
	(generator_version "10.0")
	(general
		(thickness 1.6)
		(legacy_teardrops no)
	)
	(paper "A4")
	(title_block
		(title "Wiwynn_Tioga_Pass_MB.brd")
		(comment 1 "Tioga Pass / footprints 4067-4069 of 4770")
	)
	(layers
		(0 "F.Cu" signal "TOP")
		(4 "In1.Cu" signal "L2GND")
		(6 "In2.Cu" signal "L3")
		(8 "In3.Cu" signal "L4GND")
		(10 "In4.Cu" signal "L5")
		(12 "In5.Cu" signal "L6GND")
		(14 "In6.Cu" signal "L7VCC")
		(16 "In7.Cu" signal "L8VCC")
		(18 "In8.Cu" signal "L9GND")
		(20 "In9.Cu" signal "L10")
		(22 "In10.Cu" signal "L11GND")
		(24 "In11.Cu" signal "L12")
		(26 "In12.Cu" signal "L13GND")
		(2 "B.Cu" signal "BOTTOM")
		(9 "F.Adhes" user "F.Adhesive")
		(11 "B.Adhes" user "B.Adhesive")
		(13 "F.Paste" user "Package Geometry/Pastemask Top")
		(15 "B.Paste" user "Package Geometry/Pastemask Bottom")
		(5 "F.SilkS" user "Ref Des/Silkscreen Top")
		(7 "B.SilkS" user "Ref Des/Silkscreen Bottom")
		(1 "F.Mask" user "Board Geometry/Soldermask Top")
		(3 "B.Mask" user "Board Geometry/Soldermask Bottom")
		(17 "Dwgs.User" user "User.Drawings")
		(19 "Cmts.User" user "User.Comments")
		(21 "Eco1.User" user "User.Eco1")
		(23 "Eco2.User" user "User.Eco2")
		(25 "Edge.Cuts" user "Board Geometry/Outline")
		(27 "Margin" user)
		(31 "F.CrtYd" user "Package Geometry/Place Bound Top")
		(29 "B.CrtYd" user "Package Geometry/Place Bound Bottom")
		(35 "F.Fab" user "Ref Des/Assembly Top")
		(33 "B.Fab" user "Ref Des/Assembly Bottom")
	)
	(footprint ""
		(layer "B.Cu")
		(at 376.7328 -135.5598 180)
		(property "Reference" "C3M21"
			(at 0 0 0)
			(layer "B.SilkS")
			(hide yes)
			(effects
				(font
					(size 1.27 1.27)
				)
				(justify mirror)
			)
		)
		(property "Value" ""
			(at 0 0 0)
			(layer "B.Fab")
			(effects
				(font
					(size 1.27 1.27)
				)
				(justify mirror)
			)
		)
		(duplicate_pad_numbers_are_jumpers no)
		(fp_rect
			(start 0.3048 -0.1016)
			(end -0.3048 0.9906)
			(stroke
				(width 0)
				(type default)
			)
			(fill no)
			(layer "B.CrtYd")
		)
		(fp_line
			(start 0.3048 0.9906)
			(end -0.3048 0.9906)
			(stroke
				(width 0.1)
				(type default)
			)
			(layer "B.Fab")
		)
		(fp_line
			(start 0.3048 -0.1016)
			(end 0.3048 0.9906)
			(stroke
				(width 0.1)
				(type default)
			)
			(layer "B.Fab")
		)
		(fp_line
			(start -0.3048 0.9906)
			(end -0.3048 -0.1016)
			(stroke
				(width 0.1)
				(type default)
			)
			(layer "B.Fab")
		)
		(fp_line
			(start -0.3048 -0.1016)
			(end 0.3048 -0.1016)
			(stroke
				(width 0.1)
				(type default)
			)
			(layer "B.Fab")
		)
		(pad "1" smd rect
			(at 0 0)
			(size 0.508 0.508)
			(layers "B.Cu" "B.Mask" "B.Paste")
			(net "P1V05_PCH_STBY")
		)
		(pad "2" smd rect
			(at 0 0.889)
			(size 0.508 0.508)
			(layers "B.Cu" "B.Mask" "B.Paste")
			(net "GND")
		)
		(zone
			(layer "B.Cu")
			(hatch none 0.5)
			(connect_pads
				(clearance 0)
			)
			(min_thickness 0.25)
			(keepout
				(tracks allowed)
				(vias not_allowed)
				(pads allowed)
				(copperpour not_allowed)
				(footprints allowed)
			)
			(placement
				(enabled no)
				(sheetname "")
			)
			(fill
				(thermal_gap 0.5)
				(thermal_bridge_width 0.5)
				(island_removal_mode 0)
			)
			(polygon
				(pts
					(xy 376.4788 -135.8138) (xy 376.9868 -135.8138) (xy 376.9868 -136.1948) (xy 376.4788 -136.1948)
				)
			)
		)
		(zone
			(layer "B.Cu")
			(hatch none 0.5)
			(connect_pads
				(clearance 0)
			)
			(min_thickness 0.25)
			(keepout
				(tracks not_allowed)
				(vias allowed)
				(pads allowed)
				(copperpour not_allowed)
				(footprints allowed)
			)
			(placement
				(enabled no)
				(sheetname "")
			)
			(fill
				(thermal_gap 0.5)
				(thermal_bridge_width 0.5)
				(island_removal_mode 0)
			)
			(polygon
				(pts
					(xy 376.4788 -135.8138) (xy 376.9868 -135.8138) (xy 376.9868 -136.1948) (xy 376.4788 -136.1948)
				)
			)
		)
	)
	(footprint ""
		(layer "B.Cu")
		(at 106.604054 -68.17614 180)
		(property "Reference" "C8P32"
			(at 0 0 0)
			(layer "B.SilkS")
			(hide yes)
			(effects
				(font
					(size 1.27 1.27)
				)
				(justify mirror)
			)
		)
		(property "Value" ""
			(at 0 0 0)
			(layer "B.Fab")
			(effects
				(font
					(size 1.27 1.27)
				)
				(justify mirror)
			)
		)
		(duplicate_pad_numbers_are_jumpers no)
		(fp_poly
			(pts
				(xy 0.7239 -0.2159) (xy -0.7239 -0.2159) (xy -0.7239 1.9939) (xy 0.7239 1.9939)
			)
			(stroke
				(width 0)
				(type default)
			)
			(fill no)
			(layer "B.CrtYd")
		)
		(fp_line
			(start 0.7239 1.9939)
			(end -0.7239 1.9939)
			(stroke
				(width 0.1)
				(type default)
			)
			(layer "B.Fab")
		)
		(fp_line
			(start 0.7239 -0.2159)
			(end 0.7239 1.9939)
			(stroke
				(width 0.1)
				(type default)
			)
			(layer "B.Fab")
		)
		(fp_line
			(start -0.7239 1.9939)
			(end -0.7239 -0.2159)
			(stroke
				(width 0.1)
				(type default)
			)
			(layer "B.Fab")
		)
		(fp_line
			(start -0.7239 -0.2159)
			(end 0.7239 -0.2159)
			(stroke
				(width 0.1)
				(type default)
			)
			(layer "B.Fab")
		)
		(pad "1" smd rect
			(at 0 0)
			(size 1.27 1.016)
			(layers "B.Cu" "B.Mask" "B.Paste")
			(net "PVDDQ_GHJ")
		)
		(pad "2" smd rect
			(at 0 1.778)
			(size 1.27 1.016)
			(layers "B.Cu" "B.Mask" "B.Paste")
			(net "GND")
		)
		(zone
			(layer "B.Cu")
			(hatch none 0.5)
			(connect_pads
				(clearance 0)
			)
			(min_thickness 0.25)
			(keepout
				(tracks not_allowed)
				(vias allowed)
				(pads allowed)
				(copperpour not_allowed)
				(footprints allowed)
			)
			(placement
				(enabled no)
				(sheetname "")
			)
			(fill
				(thermal_gap 0.5)
				(thermal_bridge_width 0.5)
				(island_removal_mode 0)
			)
			(polygon
				(pts
					(xy 105.969054 -68.68414) (xy 107.239054 -68.68414) (xy 107.239054 -69.44614) (xy 105.969054 -69.44614)
				)
			)
		)
	)
	(footprint ""
		(layer "B.Cu")
		(at 20.3835 -90.1065 -90)
		(property "Reference" "Q6W1"
			(at 0.229362 -1.2065 270)
			(unlocked yes)
			(layer "B.SilkS")
			(effects
				(font
					(size 0.4064 0.254)
					(thickness 0.1524)
				)
				(justify left mirror)
			)
		)
		(property "Value" ""
			(at 0 0 90)
			(layer "B.Fab")
			(effects
				(font
					(size 1.27 1.27)
				)
				(justify mirror)
			)
		)
		(duplicate_pad_numbers_are_jumpers no)
		(fp_line
			(start -1.778 2.4765)
			(end -1.778 1.5875)
			(stroke
				(width 0.1524)
				(type default)
			)
			(layer "B.SilkS")
		)
		(fp_line
			(start -0.9525 2.4765)
			(end -1.778 2.4765)
			(stroke
				(width 0.1524)
				(type default)
			)
			(layer "B.SilkS")
		)
		(fp_line
			(start -0.381 0.635)
			(end -0.381 1.27)
			(stroke
				(width 0.1524)
				(type default)
			)
			(layer "B.SilkS")
		)
		(fp_line
			(start -1.778 -0.5715)
			(end -1.778 0.3175)
			(stroke
				(width 0.1524)
				(type default)
			)
			(layer "B.SilkS")
		)
		(fp_line
			(start -0.9525 -0.5715)
			(end -1.778 -0.5715)
			(stroke
				(width 0.1524)
				(type default)
			)
			(layer "B.SilkS")
		)
		(fp_circle
			(center 0.9525 -0.9271)
			(end 0.9525 -1.0541)
			(stroke
				(width 0.254)
				(type default)
			)
			(fill no)
			(layer "B.SilkS")
		)
		(fp_poly
			(pts
				(xy -1.778 2.4765) (xy -0.381 2.4765) (xy -0.381 -0.5715) (xy -1.778 -0.5715)
			)
			(stroke
				(width 0)
				(type default)
			)
			(fill no)
			(layer "B.CrtYd")
		)
		(fp_line
			(start -1.778 2.4765)
			(end -1.778 -0.5715)
			(stroke
				(width 0.1)
				(type default)
			)
			(layer "B.Fab")
		)
		(fp_line
			(start -0.381 2.4765)
			(end -1.778 2.4765)
			(stroke
				(width 0.1)
				(type default)
			)
			(layer "B.Fab")
		)
		(fp_line
			(start -1.778 -0.5715)
			(end -0.381 -0.5715)
			(stroke
				(width 0.1)
				(type default)
			)
			(layer "B.Fab")
		)
		(fp_line
			(start -0.381 -0.5715)
			(end -0.381 2.4765)
			(stroke
				(width 0.1)
				(type default)
			)
			(layer "B.Fab")
		)
		(fp_circle
			(center 0.9525 -0.9271)
			(end 0.9525 -1.0541)
			(stroke
				(width 0.254)
				(type default)
			)
			(fill no)
			(layer "B.Fab")
		)
		(pad "1" smd rect
			(at 0 0 90)
			(size 1.143 0.508)
			(layers "B.Cu" "B.Mask" "B.Paste")
			(net "UV_HIGH_SET")
		)
		(pad "2" smd rect
			(at 0 1.905 90)
			(size 1.143 0.508)
			(layers "B.Cu" "B.Mask" "B.Paste")
			(net "GND")
		)
		(pad "3" smd rect
			(at -2.159 0.9525 90)
			(size 1.143 0.508)
			(layers "B.Cu" "B.Mask" "B.Paste")
			(net "UV_HIGH_SET_N")
		)
	)
)
